# T6G (Grand Teton) — schematic netlist excerpt (pin names and nets, part order shuffled) for the footprints in the layout excerpt that follows; sources: Cadence DE-HDL packaged netlist, KiCad conversion of 04192023_DAF0TMB3IC0_F0TG_MB_C_brd_V02_OCP.brd

R6076  Q_RES  33 5% CHIP  pkg 0402LF  page 151 : A = SMB_SCM_2_R3_SCL ; B = SMB_SCM_2_R4_SCL
R3517  Q_RES  0 5% CHIP  pkg 0402LF  page 245 : A = GPU_PEX_STRAP1 ; B = GPU_PEX_STRAP1_R

(kicad_pcb
	(version 20260206)
	(generator "pcbnew")
	(generator_version "10.0")
	(general
		(thickness 1.6)
		(legacy_teardrops no)
	)
	(paper "A4")
	(title_block
		(title "04192023_DAF0TMB3IC0_F0TG_MB_C_brd_V02_OCP.brd")
		(comment 1 "Grand Teton / footprints 452-453 of 8354")
	)
	(layers
		(0 "F.Cu" signal "TOP")
		(4 "In1.Cu" signal "GND")
		(6 "In2.Cu" signal "IN1")
		(8 "In3.Cu" signal "GND1")
		(10 "In4.Cu" signal "IN2")
		(12 "In5.Cu" signal "GND2")
		(14 "In6.Cu" signal "IN3")
		(16 "In7.Cu" signal "GND3")
		(18 "In8.Cu" signal "VCC")
		(20 "In9.Cu" signal "VCC1")
		(22 "In10.Cu" signal "GND4")
		(24 "In11.Cu" signal "IN4")
		(26 "In12.Cu" signal "GND5")
		(28 "In13.Cu" signal "IN5")
		(30 "In14.Cu" signal "GND6")
		(32 "In15.Cu" signal "IN6")
		(34 "In16.Cu" signal "GND7")
		(2 "B.Cu" signal "BOTTOM")
		(9 "F.Adhes" user "F.Adhesive")
		(11 "B.Adhes" user "B.Adhesive")
		(13 "F.Paste" user "Package Geometry/Pastemask Top")
		(15 "B.Paste" user "Package Geometry/Pastemask Bottom")
		(5 "F.SilkS" user "Ref Des/Silkscreen Top")
		(7 "B.SilkS" user "Ref Des/Silkscreen Bottom")
		(1 "F.Mask" user "Board Geometry/Soldermask Top")
		(3 "B.Mask" user "Board Geometry/Soldermask Bottom")
		(17 "Dwgs.User" user "User.Drawings")
		(19 "Cmts.User" user "User.Comments")
		(21 "Eco1.User" user "User.Eco1")
		(23 "Eco2.User" user "User.Eco2")
		(25 "Edge.Cuts" user "Board Geometry/Outline")
		(27 "Margin" user)
		(31 "F.CrtYd" user "Package Geometry/Place Bound Top")
		(29 "B.CrtYd" user "Package Geometry/Place Bound Bottom")
		(35 "F.Fab" user "Ref Des/Assembly Top")
		(33 "B.Fab" user "Ref Des/Assembly Bottom")
	)
	(footprint ""
		(layer "F.Cu")
		(at 184.310528 -426.40504 -90)
		(property "Reference" "R3517"
			(at 0 0 270)
			(layer "F.SilkS")
			(hide yes)
			(effects
				(font
					(size 1.27 1.27)
				)
			)
		)
		(property "Value" ""
			(at 0 0 270)
			(layer "F.Fab")
			(effects
				(font
					(size 1.27 1.27)
				)
			)
		)
		(duplicate_pad_numbers_are_jumpers no)
		(fp_line
			(start -0.7874 0.4064)
			(end -0.7874 -0.4064)
			(stroke
				(width 0.1524)
				(type default)
			)
			(layer "F.SilkS")
		)
		(fp_line
			(start 0.7874 0.4064)
			(end -0.7874 0.4064)
			(stroke
				(width 0.1524)
				(type default)
			)
			(layer "F.SilkS")
		)
		(fp_line
			(start -0.7874 -0.4064)
			(end 0.7874 -0.4064)
			(stroke
				(width 0.1524)
				(type default)
			)
			(layer "F.SilkS")
		)
		(fp_line
			(start 0.7874 -0.4064)
			(end 0.7874 0.4064)
			(stroke
				(width 0.1524)
				(type default)
			)
			(layer "F.SilkS")
		)
		(fp_line
			(start -0.67945 0.3048)
			(end -0.67945 -0.305054)
			(stroke
				(width 0.1)
				(type default)
			)
			(layer "F.Fab")
		)
		(fp_line
			(start -0.12065 0.3048)
			(end -0.67945 0.3048)
			(stroke
				(width 0.1)
				(type default)
			)
			(layer "F.Fab")
		)
		(fp_line
			(start 0.120396 0.3048)
			(end 0.120396 0.2794)
			(stroke
				(width 0.1)
				(type default)
			)
			(layer "F.Fab")
		)
		(fp_line
			(start 0.67945 0.3048)
			(end 0.120396 0.3048)
			(stroke
				(width 0.1)
				(type default)
			)
			(layer "F.Fab")
		)
		(fp_line
			(start -0.12065 0.2794)
			(end -0.12065 0.3048)
			(stroke
				(width 0.1)
				(type default)
			)
			(layer "F.Fab")
		)
		(fp_line
			(start 0.120396 0.2794)
			(end -0.12065 0.2794)
			(stroke
				(width 0.1)
				(type default)
			)
			(layer "F.Fab")
		)
		(fp_line
			(start -0.12065 -0.2794)
			(end 0.12065 -0.2794)
			(stroke
				(width 0.1)
				(type default)
			)
			(layer "F.Fab")
		)
		(fp_line
			(start 0.12065 -0.2794)
			(end 0.12065 -0.3048)
			(stroke
				(width 0.1)
				(type default)
			)
			(layer "F.Fab")
		)
		(fp_line
			(start 0.12065 -0.3048)
			(end 0.67945 -0.3048)
			(stroke
				(width 0.1)
				(type default)
			)
			(layer "F.Fab")
		)
		(fp_line
			(start 0.67945 -0.3048)
			(end 0.67945 0.3048)
			(stroke
				(width 0.1)
				(type default)
			)
			(layer "F.Fab")
		)
		(fp_line
			(start -0.67945 -0.305054)
			(end -0.12065 -0.305054)
			(stroke
				(width 0.1)
				(type default)
			)
			(layer "F.Fab")
		)
		(fp_line
			(start -0.12065 -0.305054)
			(end -0.12065 -0.2794)
			(stroke
				(width 0.1)
				(type default)
			)
			(layer "F.Fab")
		)
		(pad "1" smd circle
			(at -0.40005 0 270)
			(size 0 0)
			(layers "F.Cu" "F.Mask" "F.Paste")
			(net "GPU_PEX_STRAP1")
		)
		(pad "2" smd circle
			(at 0.40005 0 270)
			(size 0 0)
			(layers "F.Cu" "F.Mask" "F.Paste")
			(net "GPU_PEX_STRAP1_R")
		)
	)
	(footprint ""
		(layer "F.Cu")
		(at 388.074662 -143.323056 -90)
		(property "Reference" "R6076"
			(at 0 0 270)
			(layer "F.SilkS")
			(hide yes)
			(effects
				(font
					(size 1.27 1.27)
				)
			)
		)
		(property "Value" ""
			(at 0 0 270)
			(layer "F.Fab")
			(effects
				(font
					(size 1.27 1.27)
				)
			)
		)
		(duplicate_pad_numbers_are_jumpers no)
		(fp_line
			(start -0.7874 0.4064)
			(end -0.7874 -0.4064)
			(stroke
				(width 0.1524)
				(type default)
			)
			(layer "F.SilkS")
		)
		(fp_line
			(start 0.7874 0.4064)
			(end -0.7874 0.4064)
			(stroke
				(width 0.1524)
				(type default)
			)
			(layer "F.SilkS")
		)
		(fp_line
			(start -0.7874 -0.4064)
			(end 0.7874 -0.4064)
			(stroke
				(width 0.1524)
				(type default)
			)
			(layer "F.SilkS")
		)
		(fp_line
			(start 0.7874 -0.4064)
			(end 0.7874 0.4064)
			(stroke
				(width 0.1524)
				(type default)
			)
			(layer "F.SilkS")
		)
		(fp_line
			(start -0.67945 0.3048)
			(end -0.67945 -0.305054)
			(stroke
				(width 0.1)
				(type default)
			)
			(layer "F.Fab")
		)
		(fp_line
			(start -0.12065 0.3048)
			(end -0.67945 0.3048)
			(stroke
				(width 0.1)
				(type default)
			)
			(layer "F.Fab")
		)
		(fp_line
			(start 0.120396 0.3048)
			(end 0.120396 0.2794)
			(stroke
				(width 0.1)
				(type default)
			)
			(layer "F.Fab")
		)
		(fp_line
			(start 0.67945 0.3048)
			(end 0.120396 0.3048)
			(stroke
				(width 0.1)
				(type default)
			)
			(layer "F.Fab")
		)
		(fp_line
			(start -0.12065 0.2794)
			(end -0.12065 0.3048)
			(stroke
				(width 0.1)
				(type default)
			)
			(layer "F.Fab")
		)
		(fp_line
			(start 0.120396 0.2794)
			(end -0.12065 0.2794)
			(stroke
				(width 0.1)
				(type default)
			)
			(layer "F.Fab")
		)
		(fp_line
			(start -0.12065 -0.2794)
			(end 0.12065 -0.2794)
			(stroke
				(width 0.1)
				(type default)
			)
			(layer "F.Fab")
		)
		(fp_line
			(start 0.12065 -0.2794)
			(end 0.12065 -0.3048)
			(stroke
				(width 0.1)
				(type default)
			)
			(layer "F.Fab")
		)
		(fp_line
			(start 0.12065 -0.3048)
			(end 0.67945 -0.3048)
			(stroke
				(width 0.1)
				(type default)
			)
			(layer "F.Fab")
		)
		(fp_line
			(start 0.67945 -0.3048)
			(end 0.67945 0.3048)
			(stroke
				(width 0.1)
				(type default)
			)
			(layer "F.Fab")
		)
		(fp_line
			(start -0.67945 -0.305054)
			(end -0.12065 -0.305054)
			(stroke
				(width 0.1)
				(type default)
			)
			(layer "F.Fab")
		)
		(fp_line
			(start -0.12065 -0.305054)
			(end -0.12065 -0.2794)
			(stroke
				(width 0.1)
				(type default)
			)
			(layer "F.Fab")
		)
		(pad "1" smd circle
			(at -0.40005 0 270)
			(size 0 0)
			(layers "F.Cu" "F.Mask" "F.Paste")
			(net "SMB_SCM_2_R3_SCL")
		)
		(pad "2" smd circle
			(at 0.40005 0 270)
			(size 0 0)
			(layers "F.Cu" "F.Mask" "F.Paste")
			(net "SMB_SCM_2_R4_SCL")
		)
	)
)
